(kicad_pcb
	(version 20221018)
	(generator pcbnew)
	(general
    (thickness 1.7403)
  )
	(paper "A4")
	(title_block
    (title "Data Center RDIMM DDR4 Tester")
    (date "2024-09-30")
    (rev "1.2.4")
		(comment 9 "footprints 430-438 of 690")
	)
	(layers
    (0 "F.Cu" signal)
    (1 "In1.Cu" power)
    (2 "In2.Cu" signal)
    (3 "In3.Cu" power)
    (4 "In4.Cu" power)
    (5 "In5.Cu" signal)
    (6 "In6.Cu" power)
    (7 "In7.Cu" signal)
    (8 "In8.Cu" power)
    (9 "In9.Cu" signal)
    (10 "In10.Cu" power)
    (31 "B.Cu" signal)
    (32 "B.Adhes" user "B.Adhesive")
    (33 "F.Adhes" user "F.Adhesive")
    (34 "B.Paste" user)
    (35 "F.Paste" user)
    (36 "B.SilkS" user "B.Silkscreen")
    (37 "F.SilkS" user "F.Silkscreen")
    (38 "B.Mask" user)
    (39 "F.Mask" user)
    (40 "Dwgs.User" user "User.Drawings")
    (41 "Cmts.User" user "User.Comments")
    (42 "Eco1.User" user "User.Eco1")
    (43 "Eco2.User" user "User.Eco2")
    (44 "Edge.Cuts" user)
    (45 "Margin" user)
    (46 "B.CrtYd" user "B.Courtyard")
    (47 "F.CrtYd" user "F.Courtyard")
    (48 "B.Fab" user)
    (49 "F.Fab" user)
  )
	(footprint "data-center-rdimm-ddr4-tester-footprints:R_0402_1005Metric" (layer "B.Cu")
    (at 241.6 126.2 90)
    (descr "Resistor SMD 0402")
    (tags "resistor SMD 0402")
    (property "Author" "Antmicro")
    (property "License" "Apache-2.0")
    (property "MPN" "CR0402-FX-3300GLF")
    (property "Manufacturer" "Bourns")
    (property "Sheetfile" "config-spi.kicad_sch")
    (property "Sheetname" "Config SPI flash")
    (property "Tolerance" "1%")
    (property "Val" "330R")
    (property "ki_description" "330R resistor in 0402 package with 1% tolerance")
    (attr smd)
    (fp_text reference "R31" (at 0.98 1.33 270) (layer "B.SilkS")
        (effects (font (size 0.7 0.7) (thickness 0.15)) (justify left bottom mirror))
    )
    (fp_text value "R_330R_0402" (at 0 -1.4 270) (layer "B.Fab") hide
        (effects (font (size 0.7 0.7) (thickness 0.15)) (justify left bottom mirror))
    )
    (fp_text user "Author: Antmicro" (at -0.95 -4.169 270) (layer "B.Fab") hide
        (effects (font (size 0.7 0.7) (thickness 0.15)) (justify left bottom mirror))
    )
    (fp_text user "${REFERENCE}" (at -0.95 -3.168 270) (layer "B.Fab") hide
        (effects (font (size 0.7 0.7) (thickness 0.15)) (justify left bottom mirror))
    )
    (fp_text user "License: Apache-2.0" (at -0.95 -5.169 270) (layer "B.Fab") hide
        (effects (font (size 0.7 0.7) (thickness 0.15)) (justify left bottom mirror))
    )
    (fp_rect (start -0.93 0.47) (end 0.93 -0.47)
      (stroke (width 0.05) (type solid)) (fill none) (layer "B.CrtYd"))
    (fp_rect (start -0.5 0.25) (end 0.5 -0.25)
      (stroke (width 0.15) (type solid)) (fill none) (layer "B.Fab"))
    (pad "1" smd roundrect (at -0.485 0 90) (size 0.59 0.64) (layers "B.Cu" "B.Paste" "B.Mask") (roundrect_rratio 0.25)
      (net 90 "Net-(D10-Pad2)") (pintype "passive"))
    (pad "2" smd roundrect (at 0.485 0 90) (size 0.59 0.64) (layers "B.Cu" "B.Paste" "B.Mask") (roundrect_rratio 0.25)
      (net 580 "Net-(Q8-D)") (pintype "passive"))
  )
	(footprint "data-center-rdimm-ddr4-tester-footprints:R_0402_1005Metric" (layer "B.Cu")
    (at 237.65 123.315 -90)
    (descr "Resistor SMD 0402")
    (tags "resistor SMD 0402")
    (property "Author" "Antmicro")
    (property "License" "Apache-2.0")
    (property "MPN" "CR0402-FX-3300GLF")
    (property "Manufacturer" "Bourns")
    (property "Sheetfile" "config-spi.kicad_sch")
    (property "Sheetname" "Config SPI flash")
    (property "Tolerance" "1%")
    (property "Val" "330R")
    (property "ki_description" "330R resistor in 0402 package with 1% tolerance")
    (attr smd)
    (fp_text reference "R57" (at -1.075 0.59 90) (layer "B.SilkS")
        (effects (font (size 0.7 0.7) (thickness 0.15)) (justify left bottom mirror))
    )
    (fp_text value "R_330R_0402" (at 0 -1.4 90) (layer "B.Fab") hide
        (effects (font (size 0.7 0.7) (thickness 0.15)) (justify left bottom mirror))
    )
    (fp_text user "License: Apache-2.0" (at -0.95 -5.169 90) (layer "B.Fab") hide
        (effects (font (size 0.7 0.7) (thickness 0.15)) (justify left bottom mirror))
    )
    (fp_text user "${REFERENCE}" (at -0.95 -3.168 90) (layer "B.Fab") hide
        (effects (font (size 0.7 0.7) (thickness 0.15)) (justify left bottom mirror))
    )
    (fp_text user "Author: Antmicro" (at -0.95 -4.169 90) (layer "B.Fab") hide
        (effects (font (size 0.7 0.7) (thickness 0.15)) (justify left bottom mirror))
    )
    (fp_rect (start -0.93 0.47) (end 0.93 -0.47)
      (stroke (width 0.05) (type solid)) (fill none) (layer "B.CrtYd"))
    (fp_rect (start -0.5 0.25) (end 0.5 -0.25)
      (stroke (width 0.15) (type solid)) (fill none) (layer "B.Fab"))
    (pad "1" smd roundrect (at -0.485 0 270) (size 0.59 0.64) (layers "B.Cu" "B.Paste" "B.Mask") (roundrect_rratio 0.25)
      (net 143 "3V3_SYS") (pintype "passive"))
    (pad "2" smd roundrect (at 0.485 0 270) (size 0.59 0.64) (layers "B.Cu" "B.Paste" "B.Mask") (roundrect_rratio 0.25)
      (net 25 "DONE") (pintype "passive"))
  )
	(footprint "data-center-rdimm-ddr4-tester-footprints:C_0603_1608Metric" (layer "B.Cu")
    (at 191.707 88.049 -90)
    (descr "Capacitor SMD 0603")
    (tags "capacitor 0603")
    (property "Author" "Antmicro")
    (property "Dielectric" "")
    (property "License" "Apache-2.0")
    (property "MPN" "GRM188R60J476ME15D")
    (property "Manufacturer" "Murata")
    (property "Sheetfile" "config-spi.kicad_sch")
    (property "Sheetname" "Config SPI flash")
    (property "Val" "47u")
    (property "Voltage" "")
    (property "ki_description" " ")
    (attr smd)
    (fp_text reference "C12" (at -1.139 0.597 90) (layer "B.SilkS")
        (effects (font (size 0.7 0.7) (thickness 0.15)) (justify left bottom mirror))
    )
    (fp_text value "C_47u_0603" (at 0 -1.6 90) (layer "B.Fab") hide
        (effects (font (size 0.7 0.7) (thickness 0.15)) (justify left bottom mirror))
    )
    (fp_text user "${REFERENCE}" (at -1.682 -3.895 90) (layer "B.Fab") hide
        (effects (font (size 0.7 0.7) (thickness 0.15)) (justify left bottom mirror))
    )
    (fp_text user "License: Apache-2.0" (at -1.682 -5.895 90) (layer "B.Fab") hide
        (effects (font (size 0.7 0.7) (thickness 0.15)) (justify left bottom mirror))
    )
    (fp_text user "Author: Antmicro" (at -1.682 -4.894 90) (layer "B.Fab") hide
        (effects (font (size 0.7 0.7) (thickness 0.15)) (justify left bottom mirror))
    )
    (fp_line (start -0.3 -0.3) (end 0.3 -0.3)
      (stroke (width 0.15) (type solid)) (layer "B.SilkS"))
    (fp_line (start -0.3 0.3) (end 0.3 0.3)
      (stroke (width 0.15) (type solid)) (layer "B.SilkS"))
    (fp_rect (start -1.24 0.7) (end 1.24 -0.7)
      (stroke (width 0.05) (type solid)) (fill none) (layer "B.CrtYd"))
    (fp_rect (start -0.8 0.4) (end 0.8 -0.4)
      (stroke (width 0.15) (type solid)) (fill none) (layer "B.Fab"))
    (pad "1" smd roundrect (at -0.7 0 270) (size 0.6 0.8) (layers "B.Cu" "B.Paste" "B.Mask") (roundrect_rratio 0.2)
      (net 143 "3V3_SYS") (pintype "passive"))
    (pad "2" smd roundrect (at 0.7 0 270) (size 0.6 0.8) (layers "B.Cu" "B.Paste" "B.Mask") (roundrect_rratio 0.2)
      (net 9 "GND") (pintype "passive"))
  )
	(footprint "data-center-rdimm-ddr4-tester-footprints:C_0402_1005Metric" (layer "B.Cu")
    (at 191.775 94.425)
    (descr "Capacitor SMD 0402")
    (tags "capacitor SMD 0402")
    (property "Author" "Antmicro")
    (property "Dielectric" "")
    (property "License" "Apache-2.0")
    (property "MPN" "C1005X5R1E474M050BB")
    (property "Manufacturer" "TDK")
    (property "Sheetfile" "config-spi.kicad_sch")
    (property "Sheetname" "Config SPI flash")
    (property "Val" "470n")
    (property "Voltage" "")
    (property "ki_description" " ")
    (attr smd)
    (fp_text reference "C13" (at 3.025 0.485 180) (layer "B.SilkS")
        (effects (font (size 0.7 0.7) (thickness 0.15)) (justify left bottom mirror))
    )
    (fp_text value "C_470n_0402" (at 0 -1.4 180) (layer "B.Fab") hide
        (effects (font (size 0.7 0.7) (thickness 0.15)) (justify left bottom mirror))
    )
    (fp_text user "Author: Antmicro" (at -0.932 -4.17 180) (layer "B.Fab") hide
        (effects (font (size 0.7 0.7) (thickness 0.15)) (justify left bottom mirror))
    )
    (fp_text user "License: Apache-2.0" (at -0.932 -5.17 180) (layer "B.Fab") hide
        (effects (font (size 0.7 0.7) (thickness 0.15)) (justify left bottom mirror))
    )
    (fp_text user "${REFERENCE}" (at -0.932 -3.168 180) (layer "B.Fab") hide
        (effects (font (size 0.7 0.7) (thickness 0.15)) (justify left bottom mirror))
    )
    (fp_rect (start -0.94 0.47) (end 0.94 -0.47)
      (stroke (width 0.05) (type solid)) (fill none) (layer "B.CrtYd"))
    (fp_rect (start -0.499 0.249) (end 0.499 -0.249)
      (stroke (width 0.15) (type solid)) (fill none) (layer "B.Fab"))
    (pad "1" smd roundrect (at -0.484 0) (size 0.59 0.64) (layers "B.Cu" "B.Paste" "B.Mask") (roundrect_rratio 0.25)
      (net 143 "3V3_SYS") (pintype "passive"))
    (pad "2" smd roundrect (at 0.484 0) (size 0.59 0.64) (layers "B.Cu" "B.Paste" "B.Mask") (roundrect_rratio 0.25)
      (net 9 "GND") (pintype "passive"))
  )
	(footprint "data-center-rdimm-ddr4-tester-footprints:C_0402_1005Metric" (layer "B.Cu")
    (at 183.85 90.15)
    (descr "Capacitor SMD 0402")
    (tags "capacitor SMD 0402")
    (property "Author" "Antmicro")
    (property "Dielectric" "")
    (property "License" "Apache-2.0")
    (property "MPN" "GRM155R61A475MEAAD")
    (property "Manufacturer" "Murata")
    (property "Sheetfile" "fpga-power.kicad_sch")
    (property "Sheetname" "FPGA power")
    (property "Val" "4u7")
    (property "Voltage" "")
    (property "ki_description" " ")
    (attr smd)
    (fp_text reference "C17" (at 18.704672 -8.900008 180) (layer "B.SilkS")
        (effects (font (size 0.7 0.7) (thickness 0.15)) (justify left bottom mirror))
    )
    (fp_text value "C_4u7_0402" (at 0 -1.4 180) (layer "B.Fab") hide
        (effects (font (size 0.7 0.7) (thickness 0.15)) (justify left bottom mirror))
    )
    (fp_text user "${REFERENCE}" (at -0.932 -3.168 180) (layer "B.Fab") hide
        (effects (font (size 0.7 0.7) (thickness 0.15)) (justify left bottom mirror))
    )
    (fp_text user "Author: Antmicro" (at -0.932 -4.17 180) (layer "B.Fab") hide
        (effects (font (size 0.7 0.7) (thickness 0.15)) (justify left bottom mirror))
    )
    (fp_text user "License: Apache-2.0" (at -0.932 -5.17 180) (layer "B.Fab") hide
        (effects (font (size 0.7 0.7) (thickness 0.15)) (justify left bottom mirror))
    )
    (fp_rect (start -0.94 0.47) (end 0.94 -0.47)
      (stroke (width 0.05) (type solid)) (fill none) (layer "B.CrtYd"))
    (fp_rect (start -0.499 0.249) (end 0.499 -0.249)
      (stroke (width 0.15) (type solid)) (fill none) (layer "B.Fab"))
    (pad "1" smd roundrect (at -0.484 0) (size 0.59 0.64) (layers "B.Cu" "B.Paste" "B.Mask") (roundrect_rratio 0.25)
      (net 147 "1V0_SYS") (pintype "passive"))
    (pad "2" smd roundrect (at 0.484 0) (size 0.59 0.64) (layers "B.Cu" "B.Paste" "B.Mask") (roundrect_rratio 0.25)
      (net 9 "GND") (pintype "passive"))
  )
	(footprint "data-center-rdimm-ddr4-tester-footprints:C_0201" (layer "B.Cu")
    (at 181.736328 82.410008 180)
    (descr "Capacitor SMD 0201")
    (tags "capacitor SMD 0201")
    (property "Author" "Antmicro")
    (property "Dielectric" "")
    (property "License" "Apache-2.0")
    (property "MPN" "CC0201KRX6S5BB104")
    (property "Manufacturer" "Yaego")
    (property "Sheetfile" "fpga-power.kicad_sch")
    (property "Sheetname" "FPGA power")
    (property "Val" "100n")
    (property "Voltage" "")
    (property "ki_description" " ")
    (attr smd)
    (fp_text reference "C32" (at -1.063672 -1.249992) (layer "B.SilkS")
        (effects (font (size 0.7 0.7) (thickness 0.15)) (justify left bottom mirror))
    )
    (fp_text value "C_100n_0201" (at 0 -1.4) (layer "B.Fab") hide
        (effects (font (size 0.7 0.7) (thickness 0.15)) (justify left bottom mirror))
    )
    (fp_text user "${REFERENCE}" (at -0.72 -3.4) (layer "B.Fab") hide
        (effects (font (size 0.7 0.7) (thickness 0.15)) (justify left bottom mirror))
    )
    (fp_text user "Author: Antmicro" (at -0.72 -5.4) (layer "B.Fab") hide
        (effects (font (size 0.7 0.7) (thickness 0.15)) (justify left bottom mirror))
    )
    (fp_text user "License: Apache-2.0" (at -0.72 -4.4) (layer "B.Fab") hide
        (effects (font (size 0.7 0.7) (thickness 0.15)) (justify left bottom mirror))
    )
    (fp_rect (start -0.72 0.38) (end 0.72 -0.38)
      (stroke (width 0.05) (type solid)) (fill none) (layer "B.CrtYd"))
    (fp_rect (start 0.3 -0.15) (end -0.301 0.149)
      (stroke (width 0.15) (type solid)) (fill none) (layer "B.Fab"))
    (pad "" smd roundrect (at -0.349 0.002 180) (size 0.318 0.36) (layers "B.Paste") (roundrect_rratio 0.25))
    (pad "" smd roundrect (at 0.341 0.002 180) (size 0.318 0.36) (layers "B.Paste") (roundrect_rratio 0.25))
    (pad "1" smd roundrect (at -0.321 0.002 180) (size 0.46 0.4) (layers "B.Cu" "B.Mask") (roundrect_rratio 0.25)
      (net 77 "VDDQ") (pintype "passive"))
    (pad "2" smd roundrect (at 0.32 0.002 180) (size 0.46 0.4) (layers "B.Cu" "B.Mask") (roundrect_rratio 0.25)
      (net 9 "GND") (pintype "passive"))
  )
	(footprint "data-center-rdimm-ddr4-tester-footprints:C_0201" (layer "B.Cu")
    (at 187.5 81.2 90)
    (descr "Capacitor SMD 0201")
    (tags "capacitor SMD 0201")
    (property "Author" "Antmicro")
    (property "Dielectric" "")
    (property "License" "Apache-2.0")
    (property "MPN" "CC0201KRX6S5BB104")
    (property "Manufacturer" "Yaego")
    (property "Sheetfile" "fpga-power.kicad_sch")
    (property "Sheetname" "FPGA power")
    (property "Val" "100n")
    (property "Voltage" "")
    (property "ki_description" " ")
    (attr smd)
    (fp_text reference "C43" (at 1.4 -0.4 270) (layer "B.SilkS")
        (effects (font (size 0.7 0.7) (thickness 0.15)) (justify left bottom mirror))
    )
    (fp_text value "C_100n_0201" (at 0 -1.4 270) (layer "B.Fab") hide
        (effects (font (size 0.7 0.7) (thickness 0.15)) (justify left bottom mirror))
    )
    (fp_text user "Author: Antmicro" (at -0.72 -5.4 270) (layer "B.Fab") hide
        (effects (font (size 0.7 0.7) (thickness 0.15)) (justify left bottom mirror))
    )
    (fp_text user "License: Apache-2.0" (at -0.72 -4.4 270) (layer "B.Fab") hide
        (effects (font (size 0.7 0.7) (thickness 0.15)) (justify left bottom mirror))
    )
    (fp_text user "${REFERENCE}" (at -0.72 -3.4 270) (layer "B.Fab") hide
        (effects (font (size 0.7 0.7) (thickness 0.15)) (justify left bottom mirror))
    )
    (fp_rect (start -0.72 0.38) (end 0.72 -0.38)
      (stroke (width 0.05) (type solid)) (fill none) (layer "B.CrtYd"))
    (fp_rect (start 0.3 -0.15) (end -0.301 0.149)
      (stroke (width 0.15) (type solid)) (fill none) (layer "B.Fab"))
    (pad "" smd roundrect (at -0.349 0.002 90) (size 0.318 0.36) (layers "B.Paste") (roundrect_rratio 0.25))
    (pad "" smd roundrect (at 0.341 0.002 90) (size 0.318 0.36) (layers "B.Paste") (roundrect_rratio 0.25))
    (pad "1" smd roundrect (at -0.321 0.002 90) (size 0.46 0.4) (layers "B.Cu" "B.Mask") (roundrect_rratio 0.25)
      (net 77 "VDDQ") (pintype "passive"))
    (pad "2" smd roundrect (at 0.32 0.002 90) (size 0.46 0.4) (layers "B.Cu" "B.Mask") (roundrect_rratio 0.25)
      (net 9 "GND") (pintype "passive"))
  )
	(footprint "data-center-rdimm-ddr4-tester-footprints:C_0201" (layer "B.Cu")
    (at 182.6 80.65)
    (descr "Capacitor SMD 0201")
    (tags "capacitor SMD 0201")
    (property "Author" "Antmicro")
    (property "Dielectric" "")
    (property "License" "Apache-2.0")
    (property "MPN" "CC0201KRX6S5BB104")
    (property "Manufacturer" "Yaego")
    (property "Sheetfile" "fpga-power.kicad_sch")
    (property "Sheetname" "FPGA power")
    (property "Val" "100n")
    (property "Voltage" "")
    (property "ki_description" " ")
    (attr smd)
    (fp_text reference "C44" (at 1.04 1.19 180) (layer "B.SilkS")
        (effects (font (size 0.7 0.7) (thickness 0.15)) (justify left bottom mirror))
    )
    (fp_text value "C_100n_0201" (at 0 -1.4 180) (layer "B.Fab") hide
        (effects (font (size 0.7 0.7) (thickness 0.15)) (justify left bottom mirror))
    )
    (fp_text user "License: Apache-2.0" (at -0.72 -4.4 180) (layer "B.Fab") hide
        (effects (font (size 0.7 0.7) (thickness 0.15)) (justify left bottom mirror))
    )
    (fp_text user "${REFERENCE}" (at -0.72 -3.4 180) (layer "B.Fab") hide
        (effects (font (size 0.7 0.7) (thickness 0.15)) (justify left bottom mirror))
    )
    (fp_text user "Author: Antmicro" (at -0.72 -5.4 180) (layer "B.Fab") hide
        (effects (font (size 0.7 0.7) (thickness 0.15)) (justify left bottom mirror))
    )
    (fp_rect (start -0.72 0.38) (end 0.72 -0.38)
      (stroke (width 0.05) (type solid)) (fill none) (layer "B.CrtYd"))
    (fp_rect (start 0.3 -0.15) (end -0.301 0.149)
      (stroke (width 0.15) (type solid)) (fill none) (layer "B.Fab"))
    (pad "" smd roundrect (at -0.349 0.002) (size 0.318 0.36) (layers "B.Paste") (roundrect_rratio 0.25))
    (pad "" smd roundrect (at 0.341 0.002) (size 0.318 0.36) (layers "B.Paste") (roundrect_rratio 0.25))
    (pad "1" smd roundrect (at -0.321 0.002) (size 0.46 0.4) (layers "B.Cu" "B.Mask") (roundrect_rratio 0.25)
      (net 77 "VDDQ") (pintype "passive"))
    (pad "2" smd roundrect (at 0.32 0.002) (size 0.46 0.4) (layers "B.Cu" "B.Mask") (roundrect_rratio 0.25)
      (net 9 "GND") (pintype "passive"))
  )
	(footprint "data-center-rdimm-ddr4-tester-footprints:C_0201" (layer "B.Cu")
    (at 188.186328 91.560008 -90)
    (descr "Capacitor SMD 0201")
    (tags "capacitor SMD 0201")
    (property "Author" "Antmicro")
    (property "Dielectric" "")
    (property "License" "Apache-2.0")
    (property "MPN" "CC0201KRX6S5BB104")
    (property "Manufacturer" "Yaego")
    (property "Sheetfile" "fpga-power.kicad_sch")
    (property "Sheetname" "FPGA power")
    (property "Val" "100n")
    (property "Voltage" "")
    (property "ki_description" " ")
    (attr smd)
    (fp_text reference "C50" (at -10.180016 -18.417344 90) (layer "B.SilkS")
        (effects (font (size 0.7 0.7) (thickness 0.15)) (justify left bottom mirror))
    )
    (fp_text value "C_100n_0201" (at 0 -1.4 90) (layer "B.Fab") hide
        (effects (font (size 0.7 0.7) (thickness 0.15)) (justify left bottom mirror))
    )
    (fp_text user "${REFERENCE}" (at -0.72 -3.4 90) (layer "B.Fab") hide
        (effects (font (size 0.7 0.7) (thickness 0.15)) (justify left bottom mirror))
    )
    (fp_text user "License: Apache-2.0" (at -0.72 -4.4 90) (layer "B.Fab") hide
        (effects (font (size 0.7 0.7) (thickness 0.15)) (justify left bottom mirror))
    )
    (fp_text user "Author: Antmicro" (at -0.72 -5.4 90) (layer "B.Fab") hide
        (effects (font (size 0.7 0.7) (thickness 0.15)) (justify left bottom mirror))
    )
    (fp_rect (start -0.72 0.38) (end 0.72 -0.38)
      (stroke (width 0.05) (type solid)) (fill none) (layer "B.CrtYd"))
    (fp_rect (start 0.3 -0.15) (end -0.301 0.149)
      (stroke (width 0.15) (type solid)) (fill none) (layer "B.Fab"))
    (pad "" smd roundrect (at -0.349 0.002 270) (size 0.318 0.36) (layers "B.Paste") (roundrect_rratio 0.25))
    (pad "" smd roundrect (at 0.341 0.002 270) (size 0.318 0.36) (layers "B.Paste") (roundrect_rratio 0.25))
    (pad "1" smd roundrect (at -0.321 0.002 270) (size 0.46 0.4) (layers "B.Cu" "B.Mask") (roundrect_rratio 0.25)
      (net 147 "1V0_SYS") (pintype "passive"))
    (pad "2" smd roundrect (at 0.32 0.002 270) (size 0.46 0.4) (layers "B.Cu" "B.Mask") (roundrect_rratio 0.25)
      (net 9 "GND") (pintype "passive"))
  )
)
